#ISCELL
  mstr_misc dns *
  *
#ISCELL
  pure_quanta quanta_title_block_c *
  *
#CELL
  pure_quanta q_cap *
  page181_i1
#CELL
  pure_quanta q_cap *
  page181_i10
#ISCELL
  pure_quanta_power universal_gnd *
  page181_i11
#CELL
  pure_quanta q_res *
  page181_i12
#CELL
  pure_quanta q_cap *
  page181_i13
#ISCELL
  pure_quanta_power vcc_core *
  page181_i14
#ISCELL
  pure_quanta_power universal_gnd *
  page181_i15
#CELL
  pure_quanta q_res *
  page181_i16
#CELL
  pure_quanta q_cap *
  page181_i17
#ISCELL
  pure_quanta_power universal_gnd *
  page181_i18
#CELL
  pure_quanta q_cap *
  page181_i19
#ISCELL
  pure_quanta_power universal_gnd *
  page181_i2
#ISCELL
  pure_quanta_power universal_gnd *
  page181_i20
#CELL
  pure_quanta q_res *
  page181_i21
#ISCELL
  standard offpage *
  page181_i22
#ISCELL
  standard offpage *
  page181_i23
#ISCELL
  standard offpage *
  page181_i24
#ISCELL
  standard offpage *
  page181_i25
#ISCELL
  pure_quanta_power universal_gnd *
  page181_i26
#CELL
  pure_quanta q_cap *
  page181_i27
#CELL
  pure_quanta q_res *
  page181_i28
#ISCELL
  pure_quanta_power universal_gnd *
  page181_i29
#ISCELL
  pure_quanta_power universal_gnd *
  page181_i3
#CELL
  pure_quanta q_cap *
  page181_i30
#ISCELL
  pure_quanta_power vcc_core *
  page181_i31
#CELL
  pure_quanta isl99390frztr5935 *
  page181_i32
#ISCELL
  pure_quanta_power universal_gnd *
  page181_i33
#CELL
  pure_quanta q_res *
  page181_i34
#CELL
  pure_quanta q_cap *
  page181_i35
#CELL
  pure_quanta q_cap *
  page181_i36
#ISCELL
  pure_quanta_power universal_gnd *
  page181_i37
#CELL
  pure_quanta q_res *
  page181_i38
#CELL
  pure_quanta q_cap *
  page181_i39
#CELL
  pure_quanta q_res *
  page181_i4
#ISCELL
  pure_quanta_power universal_gnd *
  page181_i40
#CELL
  pure_quanta q_res *
  page181_i41
#CELL
  pure_quanta q_inductor4p_14 *
  page181_i42
#CELL
  pure_quanta q_inductor *
  page181_i43
#CELL
  pure_quanta q_cap *
  page181_i44
#CELL
  pure_quanta q_cap *
  page181_i45
#CELL
  pure_quanta q_cap *
  page181_i46
#CELL
  pure_quanta q_cap *
  page181_i47
#ISCELL
  pure_quanta_power universal_gnd *
  page181_i48
#CELL
  pure_quanta q_cap *
  page181_i49
#ISCELL
  standard offpage *
  page181_i5
#CELL
  pure_quanta q_res *
  page181_i50
#ISCELL
  pure_quanta_power vcc_core *
  page181_i51
#ISCELL
  standard offpage *
  page181_i52
#CELL
  pure_quanta q_cap *
  page181_i53
#ISCELL
  pure_quanta_power universal_gnd *
  page181_i54
#CELL
  pure_quanta q_res *
  page181_i55
#CELL
  pure_quanta q_cap *
  page181_i56
#ISCELL
  standard offpage *
  page181_i57
#CELL
  pure_quanta q_cap *
  page181_i58
#CELL
  pure_quanta q_cap *
  page181_i59
#ISCELL
  standard offpage *
  page181_i6
#CELL
  pure_quanta q_cap *
  page181_i60
#CELL
  pure_quanta q_inductor4p_14 *
  page181_i61
#ISCELL
  pure_quanta_power universal_gnd *
  page181_i62
#CELL
  pure_quanta q_cap *
  page181_i63
#ISCELL
  pure_quanta_power vcc_core *
  page181_i64
#ISCELL
  standard offpage *
  page181_i65
#CELL
  pure_quanta q_cap *
  page181_i66
#ISCELL
  pure_quanta_power universal_gnd *
  page181_i67
#CELL
  pure_quanta q_cap *
  page181_i68
#ISCELL
  pure_quanta_power vcc_core *
  page181_i69
#ISCELL
  standard offpage *
  page181_i7
#ISCELL
  pure_quanta_power universal_gnd *
  page181_i70
#CELL
  pure_quanta q_cap *
  page181_i71
#ISCELL
  pure_quanta_power vcc_core *
  page181_i72
#CELL
  pure_quanta isl99390frztr5935 *
  page181_i73
#ISCELL
  standard offpage *
  page181_i8
#ISCELL
  pure_quanta_power universal_gnd *
  page181_i9
